(kicad_pcb
	(version 20260206)
	(generator "pcbnew")
	(generator_version "10.0")
	(general
		(thickness 1.6)
		(legacy_teardrops no)
	)
	(paper "A4")
	(title_block
		(title "04192023_DAF0TMB3IC0_F0TG_MB_C_brd_V02_OCP.brd")
		(comment 1 "Grand Teton / footprints 281-287 of 8354")
	)
	(layers
		(0 "F.Cu" signal "TOP")
		(4 "In1.Cu" signal "GND")
		(6 "In2.Cu" signal "IN1")
		(8 "In3.Cu" signal "GND1")
		(10 "In4.Cu" signal "IN2")
		(12 "In5.Cu" signal "GND2")
		(14 "In6.Cu" signal "IN3")
		(16 "In7.Cu" signal "GND3")
		(18 "In8.Cu" signal "VCC")
		(20 "In9.Cu" signal "VCC1")
		(22 "In10.Cu" signal "GND4")
		(24 "In11.Cu" signal "IN4")
		(26 "In12.Cu" signal "GND5")
		(28 "In13.Cu" signal "IN5")
		(30 "In14.Cu" signal "GND6")
		(32 "In15.Cu" signal "IN6")
		(34 "In16.Cu" signal "GND7")
		(2 "B.Cu" signal "BOTTOM")
		(9 "F.Adhes" user "F.Adhesive")
		(11 "B.Adhes" user "B.Adhesive")
		(13 "F.Paste" user "Package Geometry/Pastemask Top")
		(15 "B.Paste" user "Package Geometry/Pastemask Bottom")
		(5 "F.SilkS" user "Ref Des/Silkscreen Top")
		(7 "B.SilkS" user "Ref Des/Silkscreen Bottom")
		(1 "F.Mask" user "Board Geometry/Soldermask Top")
		(3 "B.Mask" user "Board Geometry/Soldermask Bottom")
		(17 "Dwgs.User" user "User.Drawings")
		(19 "Cmts.User" user "User.Comments")
		(21 "Eco1.User" user "User.Eco1")
		(23 "Eco2.User" user "User.Eco2")
		(25 "Edge.Cuts" user "Board Geometry/Outline")
		(27 "Margin" user)
		(31 "F.CrtYd" user "Package Geometry/Place Bound Top")
		(29 "B.CrtYd" user "Package Geometry/Place Bound Bottom")
		(35 "F.Fab" user "Ref Des/Assembly Top")
		(33 "B.Fab" user "Ref Des/Assembly Bottom")
	)
	(footprint ""
		(layer "F.Cu")
		(at 397.064992 -172.51934 -90)
		(property "Reference" "PR360"
			(at 0 0 270)
			(layer "F.SilkS")
			(hide yes)
			(effects
				(font
					(size 1.27 1.27)
				)
			)
		)
		(property "Value" ""
			(at 0 0 270)
			(layer "F.Fab")
			(effects
				(font
					(size 1.27 1.27)
				)
			)
		)
		(duplicate_pad_numbers_are_jumpers no)
		(fp_line
			(start -0.7874 0.4064)
			(end -0.7874 -0.4064)
			(stroke
				(width 0.1524)
				(type default)
			)
			(layer "F.SilkS")
		)
		(fp_line
			(start 0.7874 0.4064)
			(end -0.7874 0.4064)
			(stroke
				(width 0.1524)
				(type default)
			)
			(layer "F.SilkS")
		)
		(fp_line
			(start -0.7874 -0.4064)
			(end 0.7874 -0.4064)
			(stroke
				(width 0.1524)
				(type default)
			)
			(layer "F.SilkS")
		)
		(fp_line
			(start 0.7874 -0.4064)
			(end 0.7874 0.4064)
			(stroke
				(width 0.1524)
				(type default)
			)
			(layer "F.SilkS")
		)
		(fp_line
			(start -0.67945 0.3048)
			(end -0.67945 -0.305054)
			(stroke
				(width 0.1)
				(type default)
			)
			(layer "F.Fab")
		)
		(fp_line
			(start -0.12065 0.3048)
			(end -0.67945 0.3048)
			(stroke
				(width 0.1)
				(type default)
			)
			(layer "F.Fab")
		)
		(fp_line
			(start 0.120396 0.3048)
			(end 0.120396 0.2794)
			(stroke
				(width 0.1)
				(type default)
			)
			(layer "F.Fab")
		)
		(fp_line
			(start 0.67945 0.3048)
			(end 0.120396 0.3048)
			(stroke
				(width 0.1)
				(type default)
			)
			(layer "F.Fab")
		)
		(fp_line
			(start -0.12065 0.2794)
			(end -0.12065 0.3048)
			(stroke
				(width 0.1)
				(type default)
			)
			(layer "F.Fab")
		)
		(fp_line
			(start 0.120396 0.2794)
			(end -0.12065 0.2794)
			(stroke
				(width 0.1)
				(type default)
			)
			(layer "F.Fab")
		)
		(fp_line
			(start -0.12065 -0.2794)
			(end 0.12065 -0.2794)
			(stroke
				(width 0.1)
				(type default)
			)
			(layer "F.Fab")
		)
		(fp_line
			(start 0.12065 -0.2794)
			(end 0.12065 -0.3048)
			(stroke
				(width 0.1)
				(type default)
			)
			(layer "F.Fab")
		)
		(fp_line
			(start 0.12065 -0.3048)
			(end 0.67945 -0.3048)
			(stroke
				(width 0.1)
				(type default)
			)
			(layer "F.Fab")
		)
		(fp_line
			(start 0.67945 -0.3048)
			(end 0.67945 0.3048)
			(stroke
				(width 0.1)
				(type default)
			)
			(layer "F.Fab")
		)
		(fp_line
			(start -0.67945 -0.305054)
			(end -0.12065 -0.305054)
			(stroke
				(width 0.1)
				(type default)
			)
			(layer "F.Fab")
		)
		(fp_line
			(start -0.12065 -0.305054)
			(end -0.12065 -0.2794)
			(stroke
				(width 0.1)
				(type default)
			)
			(layer "F.Fab")
		)
		(pad "1" smd circle
			(at -0.40005 0 270)
			(size 0 0)
			(layers "F.Cu" "F.Mask" "F.Paste")
			(net "SW_PVDDCR_SOC_P0_BOOT1")
		)
		(pad "2" smd circle
			(at 0.40005 0 270)
			(size 0 0)
			(layers "F.Cu" "F.Mask" "F.Paste")
			(net "SW_PVDDCR_SOC_P0_BOOT1_RC")
		)
	)
	(footprint ""
		(layer "F.Cu")
		(at 179.959 -129.377948 -90)
		(property "Reference" "R273"
			(at 0 0 270)
			(layer "F.SilkS")
			(hide yes)
			(effects
				(font
					(size 1.27 1.27)
				)
			)
		)
		(property "Value" ""
			(at 0 0 270)
			(layer "F.Fab")
			(effects
				(font
					(size 1.27 1.27)
				)
			)
		)
		(duplicate_pad_numbers_are_jumpers no)
		(fp_line
			(start -0.7874 0.4064)
			(end -0.7874 -0.4064)
			(stroke
				(width 0.1524)
				(type default)
			)
			(layer "F.SilkS")
		)
		(fp_line
			(start 0.7874 0.4064)
			(end -0.7874 0.4064)
			(stroke
				(width 0.1524)
				(type default)
			)
			(layer "F.SilkS")
		)
		(fp_line
			(start -0.7874 -0.4064)
			(end 0.7874 -0.4064)
			(stroke
				(width 0.1524)
				(type default)
			)
			(layer "F.SilkS")
		)
		(fp_line
			(start 0.7874 -0.4064)
			(end 0.7874 0.4064)
			(stroke
				(width 0.1524)
				(type default)
			)
			(layer "F.SilkS")
		)
		(fp_line
			(start -0.67945 0.3048)
			(end -0.67945 -0.305054)
			(stroke
				(width 0.1)
				(type default)
			)
			(layer "F.Fab")
		)
		(fp_line
			(start -0.12065 0.3048)
			(end -0.67945 0.3048)
			(stroke
				(width 0.1)
				(type default)
			)
			(layer "F.Fab")
		)
		(fp_line
			(start 0.120396 0.3048)
			(end 0.120396 0.2794)
			(stroke
				(width 0.1)
				(type default)
			)
			(layer "F.Fab")
		)
		(fp_line
			(start 0.67945 0.3048)
			(end 0.120396 0.3048)
			(stroke
				(width 0.1)
				(type default)
			)
			(layer "F.Fab")
		)
		(fp_line
			(start -0.12065 0.2794)
			(end -0.12065 0.3048)
			(stroke
				(width 0.1)
				(type default)
			)
			(layer "F.Fab")
		)
		(fp_line
			(start 0.120396 0.2794)
			(end -0.12065 0.2794)
			(stroke
				(width 0.1)
				(type default)
			)
			(layer "F.Fab")
		)
		(fp_line
			(start -0.12065 -0.2794)
			(end 0.12065 -0.2794)
			(stroke
				(width 0.1)
				(type default)
			)
			(layer "F.Fab")
		)
		(fp_line
			(start 0.12065 -0.2794)
			(end 0.12065 -0.3048)
			(stroke
				(width 0.1)
				(type default)
			)
			(layer "F.Fab")
		)
		(fp_line
			(start 0.12065 -0.3048)
			(end 0.67945 -0.3048)
			(stroke
				(width 0.1)
				(type default)
			)
			(layer "F.Fab")
		)
		(fp_line
			(start 0.67945 -0.3048)
			(end 0.67945 0.3048)
			(stroke
				(width 0.1)
				(type default)
			)
			(layer "F.Fab")
		)
		(fp_line
			(start -0.67945 -0.305054)
			(end -0.12065 -0.305054)
			(stroke
				(width 0.1)
				(type default)
			)
			(layer "F.Fab")
		)
		(fp_line
			(start -0.12065 -0.305054)
			(end -0.12065 -0.2794)
			(stroke
				(width 0.1)
				(type default)
			)
			(layer "F.Fab")
		)
		(pad "1" smd circle
			(at -0.40005 0 270)
			(size 0 0)
			(layers "F.Cu" "F.Mask" "F.Paste")
			(net "RST_CPU1_RSMRST_N")
		)
		(pad "2" smd circle
			(at 0.40005 0 270)
			(size 0 0)
			(layers "F.Cu" "F.Mask" "F.Paste")
			(net "FM_CPU1_RSMRST_N")
		)
	)
	(footprint ""
		(layer "F.Cu")
		(at 150.502366 -58.236358)
		(property "Reference" "R3610"
			(at 0 0 0)
			(layer "F.SilkS")
			(hide yes)
			(effects
				(font
					(size 1.27 1.27)
				)
			)
		)
		(property "Value" ""
			(at 0 0 0)
			(layer "F.Fab")
			(effects
				(font
					(size 1.27 1.27)
				)
			)
		)
		(duplicate_pad_numbers_are_jumpers no)
		(fp_line
			(start -0.7874 -0.4064)
			(end 0.7874 -0.4064)
			(stroke
				(width 0.1524)
				(type default)
			)
			(layer "F.SilkS")
		)
		(fp_line
			(start -0.7874 0.4064)
			(end -0.7874 -0.4064)
			(stroke
				(width 0.1524)
				(type default)
			)
			(layer "F.SilkS")
		)
		(fp_line
			(start 0.7874 -0.4064)
			(end 0.7874 0.4064)
			(stroke
				(width 0.1524)
				(type default)
			)
			(layer "F.SilkS")
		)
		(fp_line
			(start 0.7874 0.4064)
			(end -0.7874 0.4064)
			(stroke
				(width 0.1524)
				(type default)
			)
			(layer "F.SilkS")
		)
		(fp_line
			(start -0.67945 -0.305054)
			(end -0.12065 -0.305054)
			(stroke
				(width 0.1)
				(type default)
			)
			(layer "F.Fab")
		)
		(fp_line
			(start -0.67945 0.3048)
			(end -0.67945 -0.305054)
			(stroke
				(width 0.1)
				(type default)
			)
			(layer "F.Fab")
		)
		(fp_line
			(start -0.12065 -0.305054)
			(end -0.12065 -0.2794)
			(stroke
				(width 0.1)
				(type default)
			)
			(layer "F.Fab")
		)
		(fp_line
			(start -0.12065 -0.2794)
			(end 0.12065 -0.2794)
			(stroke
				(width 0.1)
				(type default)
			)
			(layer "F.Fab")
		)
		(fp_line
			(start -0.12065 0.2794)
			(end -0.12065 0.3048)
			(stroke
				(width 0.1)
				(type default)
			)
			(layer "F.Fab")
		)
		(fp_line
			(start -0.12065 0.3048)
			(end -0.67945 0.3048)
			(stroke
				(width 0.1)
				(type default)
			)
			(layer "F.Fab")
		)
		(fp_line
			(start 0.120396 0.2794)
			(end -0.12065 0.2794)
			(stroke
				(width 0.1)
				(type default)
			)
			(layer "F.Fab")
		)
		(fp_line
			(start 0.120396 0.3048)
			(end 0.120396 0.2794)
			(stroke
				(width 0.1)
				(type default)
			)
			(layer "F.Fab")
		)
		(fp_line
			(start 0.12065 -0.3048)
			(end 0.67945 -0.3048)
			(stroke
				(width 0.1)
				(type default)
			)
			(layer "F.Fab")
		)
		(fp_line
			(start 0.12065 -0.2794)
			(end 0.12065 -0.3048)
			(stroke
				(width 0.1)
				(type default)
			)
			(layer "F.Fab")
		)
		(fp_line
			(start 0.67945 -0.3048)
			(end 0.67945 0.3048)
			(stroke
				(width 0.1)
				(type default)
			)
			(layer "F.Fab")
		)
		(fp_line
			(start 0.67945 0.3048)
			(end 0.120396 0.3048)
			(stroke
				(width 0.1)
				(type default)
			)
			(layer "F.Fab")
		)
		(pad "1" smd circle
			(at -0.40005 0)
			(size 0 0)
			(layers "F.Cu" "F.Mask" "F.Paste")
			(net "GND")
		)
		(pad "2" smd circle
			(at 0.40005 0)
			(size 0 0)
			(layers "F.Cu" "F.Mask" "F.Paste")
			(net "INA230_4_A1")
		)
	)
	(footprint ""
		(layer "F.Cu")
		(at 325.697342 -398.34058)
		(property "Reference" "R1370"
			(at 0 0 0)
			(layer "F.SilkS")
			(hide yes)
			(effects
				(font
					(size 1.27 1.27)
				)
			)
		)
		(property "Value" ""
			(at 0 0 0)
			(layer "F.Fab")
			(effects
				(font
					(size 1.27 1.27)
				)
			)
		)
		(duplicate_pad_numbers_are_jumpers no)
		(fp_line
			(start -0.32512 -0.175006)
			(end 0.32512 -0.175006)
			(stroke
				(width 0.1)
				(type default)
			)
			(layer "F.Fab")
		)
		(fp_line
			(start -0.32512 0.175006)
			(end -0.32512 -0.175006)
			(stroke
				(width 0.1)
				(type default)
			)
			(layer "F.Fab")
		)
		(fp_line
			(start 0.32512 -0.175006)
			(end 0.32512 0.175006)
			(stroke
				(width 0.1)
				(type default)
			)
			(layer "F.Fab")
		)
		(fp_line
			(start 0.32512 0.175006)
			(end -0.32512 0.175006)
			(stroke
				(width 0.1)
				(type default)
			)
			(layer "F.Fab")
		)
		(pad "1" smd rect
			(at -0.2667 0)
			(size 0.3048 0.381)
			(layers "F.Cu" "F.Mask" "F.Paste")
			(net "RXDET_BYP_RT_CPU0_P0")
		)
		(pad "2" smd rect
			(at 0.2667 0 180)
			(size 0.3048 0.381)
			(layers "F.Cu" "F.Mask" "F.Paste")
			(net "GND")
		)
	)
	(footprint ""
		(layer "F.Cu")
		(at 144.315688 -394.166852 -90)
		(property "Reference" "R867"
			(at 0 0 270)
			(layer "F.SilkS")
			(hide yes)
			(effects
				(font
					(size 1.27 1.27)
				)
			)
		)
		(property "Value" ""
			(at 0 0 270)
			(layer "F.Fab")
			(effects
				(font
					(size 1.27 1.27)
				)
			)
		)
		(duplicate_pad_numbers_are_jumpers no)
		(fp_line
			(start -0.32512 0.175006)
			(end -0.32512 -0.175006)
			(stroke
				(width 0.1)
				(type default)
			)
			(layer "F.Fab")
		)
		(fp_line
			(start 0.32512 0.175006)
			(end -0.32512 0.175006)
			(stroke
				(width 0.1)
				(type default)
			)
			(layer "F.Fab")
		)
		(fp_line
			(start -0.32512 -0.175006)
			(end 0.32512 -0.175006)
			(stroke
				(width 0.1)
				(type default)
			)
			(layer "F.Fab")
		)
		(fp_line
			(start 0.32512 -0.175006)
			(end 0.32512 0.175006)
			(stroke
				(width 0.1)
				(type default)
			)
			(layer "F.Fab")
		)
		(pad "1" smd rect
			(at -0.2667 0 270)
			(size 0.3048 0.381)
			(layers "F.Cu" "F.Mask" "F.Paste")
			(net "RST_RT_CPU1_P2_RESET_R_N")
		)
		(pad "2" smd rect
			(at 0.2667 0 90)
			(size 0.3048 0.381)
			(layers "F.Cu" "F.Mask" "F.Paste")
			(net "GND")
		)
	)
	(footprint ""
		(layer "F.Cu")
		(at 152.849326 -35.97656)
		(property "Reference" "R3264"
			(at 0 0 0)
			(layer "F.SilkS")
			(hide yes)
			(effects
				(font
					(size 1.27 1.27)
				)
			)
		)
		(property "Value" ""
			(at 0 0 0)
			(layer "F.Fab")
			(effects
				(font
					(size 1.27 1.27)
				)
			)
		)
		(duplicate_pad_numbers_are_jumpers no)
		(fp_line
			(start -0.7874 -0.4064)
			(end 0.7874 -0.4064)
			(stroke
				(width 0.1524)
				(type default)
			)
			(layer "F.SilkS")
		)
		(fp_line
			(start -0.7874 0.4064)
			(end -0.7874 -0.4064)
			(stroke
				(width 0.1524)
				(type default)
			)
			(layer "F.SilkS")
		)
		(fp_line
			(start 0.7874 -0.4064)
			(end 0.7874 0.4064)
			(stroke
				(width 0.1524)
				(type default)
			)
			(layer "F.SilkS")
		)
		(fp_line
			(start 0.7874 0.4064)
			(end -0.7874 0.4064)
			(stroke
				(width 0.1524)
				(type default)
			)
			(layer "F.SilkS")
		)
		(fp_line
			(start -0.67945 -0.305054)
			(end -0.12065 -0.305054)
			(stroke
				(width 0.1)
				(type default)
			)
			(layer "F.Fab")
		)
		(fp_line
			(start -0.67945 0.3048)
			(end -0.67945 -0.305054)
			(stroke
				(width 0.1)
				(type default)
			)
			(layer "F.Fab")
		)
		(fp_line
			(start -0.12065 -0.305054)
			(end -0.12065 -0.2794)
			(stroke
				(width 0.1)
				(type default)
			)
			(layer "F.Fab")
		)
		(fp_line
			(start -0.12065 -0.2794)
			(end 0.12065 -0.2794)
			(stroke
				(width 0.1)
				(type default)
			)
			(layer "F.Fab")
		)
		(fp_line
			(start -0.12065 0.2794)
			(end -0.12065 0.3048)
			(stroke
				(width 0.1)
				(type default)
			)
			(layer "F.Fab")
		)
		(fp_line
			(start -0.12065 0.3048)
			(end -0.67945 0.3048)
			(stroke
				(width 0.1)
				(type default)
			)
			(layer "F.Fab")
		)
		(fp_line
			(start 0.120396 0.2794)
			(end -0.12065 0.2794)
			(stroke
				(width 0.1)
				(type default)
			)
			(layer "F.Fab")
		)
		(fp_line
			(start 0.120396 0.3048)
			(end 0.120396 0.2794)
			(stroke
				(width 0.1)
				(type default)
			)
			(layer "F.Fab")
		)
		(fp_line
			(start 0.12065 -0.3048)
			(end 0.67945 -0.3048)
			(stroke
				(width 0.1)
				(type default)
			)
			(layer "F.Fab")
		)
		(fp_line
			(start 0.12065 -0.2794)
			(end 0.12065 -0.3048)
			(stroke
				(width 0.1)
				(type default)
			)
			(layer "F.Fab")
		)
		(fp_line
			(start 0.67945 -0.3048)
			(end 0.67945 0.3048)
			(stroke
				(width 0.1)
				(type default)
			)
			(layer "F.Fab")
		)
		(fp_line
			(start 0.67945 0.3048)
			(end 0.120396 0.3048)
			(stroke
				(width 0.1)
				(type default)
			)
			(layer "F.Fab")
		)
		(pad "1" smd circle
			(at -0.40005 0)
			(size 0 0)
			(layers "F.Cu" "F.Mask" "F.Paste")
			(net "HP_LVC3_OCP_V3_2_R_EN")
		)
		(pad "2" smd circle
			(at 0.40005 0)
			(size 0 0)
			(layers "F.Cu" "F.Mask" "F.Paste")
			(net "P3V3_OCP_V3_2_EN_R")
		)
	)
	(footprint ""
		(layer "F.Cu")
		(at 442.233558 -168.710864 180)
		(property "Reference" "R5016"
			(at 0 0 180)
			(layer "F.SilkS")
			(hide yes)
			(effects
				(font
					(size 1.27 1.27)
				)
			)
		)
		(property "Value" ""
			(at 0 0 180)
			(layer "F.Fab")
			(effects
				(font
					(size 1.27 1.27)
				)
			)
		)
		(duplicate_pad_numbers_are_jumpers no)
		(fp_line
			(start 0.7874 0.4064)
			(end -0.7874 0.4064)
			(stroke
				(width 0.1524)
				(type default)
			)
			(layer "F.SilkS")
		)
		(fp_line
			(start 0.7874 -0.4064)
			(end 0.7874 0.4064)
			(stroke
				(width 0.1524)
				(type default)
			)
			(layer "F.SilkS")
		)
		(fp_line
			(start -0.7874 0.4064)
			(end -0.7874 -0.4064)
			(stroke
				(width 0.1524)
				(type default)
			)
			(layer "F.SilkS")
		)
		(fp_line
			(start -0.7874 -0.4064)
			(end 0.7874 -0.4064)
			(stroke
				(width 0.1524)
				(type default)
			)
			(layer "F.SilkS")
		)
		(fp_line
			(start 0.67945 0.3048)
			(end 0.120396 0.3048)
			(stroke
				(width 0.1)
				(type default)
			)
			(layer "F.Fab")
		)
		(fp_line
			(start 0.67945 -0.3048)
			(end 0.67945 0.3048)
			(stroke
				(width 0.1)
				(type default)
			)
			(layer "F.Fab")
		)
		(fp_line
			(start 0.12065 -0.2794)
			(end 0.12065 -0.3048)
			(stroke
				(width 0.1)
				(type default)
			)
			(layer "F.Fab")
		)
		(fp_line
			(start 0.12065 -0.3048)
			(end 0.67945 -0.3048)
			(stroke
				(width 0.1)
				(type default)
			)
			(layer "F.Fab")
		)
		(fp_line
			(start 0.120396 0.3048)
			(end 0.120396 0.2794)
			(stroke
				(width 0.1)
				(type default)
			)
			(layer "F.Fab")
		)
		(fp_line
			(start 0.120396 0.2794)
			(end -0.12065 0.2794)
			(stroke
				(width 0.1)
				(type default)
			)
			(layer "F.Fab")
		)
		(fp_line
			(start -0.12065 0.3048)
			(end -0.67945 0.3048)
			(stroke
				(width 0.1)
				(type default)
			)
			(layer "F.Fab")
		)
		(fp_line
			(start -0.12065 0.2794)
			(end -0.12065 0.3048)
			(stroke
				(width 0.1)
				(type default)
			)
			(layer "F.Fab")
		)
		(fp_line
			(start -0.12065 -0.2794)
			(end 0.12065 -0.2794)
			(stroke
				(width 0.1)
				(type default)
			)
			(layer "F.Fab")
		)
		(fp_line
			(start -0.12065 -0.305054)
			(end -0.12065 -0.2794)
			(stroke
				(width 0.1)
				(type default)
			)
			(layer "F.Fab")
		)
		(fp_line
			(start -0.67945 0.3048)
			(end -0.67945 -0.305054)
			(stroke
				(width 0.1)
				(type default)
			)
			(layer "F.Fab")
		)
		(fp_line
			(start -0.67945 -0.305054)
			(end -0.12065 -0.305054)
			(stroke
				(width 0.1)
				(type default)
			)
			(layer "F.Fab")
		)
		(pad "1" smd circle
			(at -0.40005 0 180)
			(size 0 0)
			(layers "F.Cu" "F.Mask" "F.Paste")
			(net "PVDD11_S3_P0")
		)
		(pad "2" smd circle
			(at 0.40005 0 180)
			(size 0 0)
			(layers "F.Cu" "F.Mask" "F.Paste")
			(net "I3C_SCM_1_R_SCL")
		)
	)
)
